# S9S_MB_2U (Grand Teton) — schematic netlist excerpt (pin names and nets, part order shuffled) for the footprints in the layout excerpt that follows; sources: Cadence DE-HDL packaged netlist, KiCad conversion of 03242023_DA0F0TMBIJ0_F0T_Motherboard_J_brd_V01_OCP.brd

J23  SCONN288_ADR50017P130CC  SCONN288_ADR50017-P130CC IO  pkg DDR288S_1-1VXB  page 104
  VIN_BULK0  = P12V_S3_AUX_CPU1_NVDIMM
  RFU0  = TP_CHD_CPU1_DIMM1_FRU_0
  VIN_MGMT  = P3V3_AUX
  HSCL  = I3C_SPD_DDRABCD_CPU1_LVC1_SCL_6
  HSDA  = I3C_SPD_DDRABCD_CPU1_LVC1_SDA
  VSS0  = GND
  DQ0_A  = M_D_CPU1_SA_DQ<0>
  VSS1  = GND
  DQ1_A  = M_D_CPU1_SA_DQ<1>
  VSS2  = GND
  DQS0_A_T  = M_D_CPU1_SA_DQS_DP<0>
  DQS0_A_C  = M_D_CPU1_SA_DQS_DN<0>
  VSS3  = GND
  DQ4_A  = M_D_CPU1_SA_DQ<4>
  VSS4  = GND
  DQ5_A  = M_D_CPU1_SA_DQ<5>
  VSS5  = GND
  DQ8_A  = M_D_CPU1_SA_DQ<8>
  VSS6  = GND
  DQ9_A  = M_D_CPU1_SA_DQ<9>
  VSS7  = GND
  DQS1_A_T  = M_D_CPU1_SA_DQS_DP<1>
  DQS1_A_C  = M_D_CPU1_SA_DQS_DN<1>
  VSS8  = GND
  DQ12_A  = M_D_CPU1_SA_DQ<12>
  VSS9  = GND
  DQ13_A  = M_D_CPU1_SA_DQ<13>
  VSS10  = GND
  DQ16_A  = M_D_CPU1_SA_DQ<16>
  VSS11  = GND
  DQ17_A  = M_D_CPU1_SA_DQ<17>
  VSS12  = GND
  DQS2_A_T  = M_D_CPU1_SA_DQS_DP<2>
  DQS2_A_C  = M_D_CPU1_SA_DQS_DN<2>
  VSS13  = GND
  DQ20_A  = M_D_CPU1_SA_DQ<20>
  VSS14  = GND
  DQ21_A  = M_D_CPU1_SA_DQ<21>
  VSS15  = GND
  DQ24_A  = M_D_CPU1_SA_DQ<24>
  VSS16  = GND
  DQ25_A  = M_D_CPU1_SA_DQ<25>
  VSS17  = GND
  DQS3_A_T  = M_D_CPU1_SA_DQS_DP<3>
  DQS3_A_C  = M_D_CPU1_SA_DQS_DN<3>
  VSS18  = GND
  DQ28_A  = M_D_CPU1_SA_DQ<28>
  VSS19  = GND
  DQ29_A  = M_D_CPU1_SA_DQ<29>
  VSS20  = GND
  CB0_A  = M_D_CPU1_SA_CB<0>
  VSS21  = GND
  CB1_A  = M_D_CPU1_SA_CB<1>
  VSS22  = GND
  DQS4_A_T  = M_D_CPU1_SA_DQS_DP<4>
  DQS4_A_C  = M_D_CPU1_SA_DQS_DN<4>
  VSS23  = GND
  CB4_A  = M_D_CPU1_SA_CB<4>
  VSS24  = GND
  CB5_A  = M_D_CPU1_SA_CB<5>
  VSS25  = GND
  ALERT_N  = M_D_CPU1_ALERT_N
  VSS26  = GND
  CS0_A_N  = M_D_CPU1_SA_CS_N<0>
  VSS27  = GND
  CA0_A  = M_D_CPU1_SA_CA<0>
  VSS28  = GND
  CA2_A  = M_D_CPU1_SA_CA<2>
  VSS29  = GND
  CA4_A  = M_D_CPU1_SA_CA<4>
  VSS30  = GND
  CA6_A  = M_D_CPU1_SA_CA<6>
  VSS31  = GND
  PAR_A  = M_D_CPU1_SA_PAR
  VSS32  = GND
  CA0_B  = M_D_CPU1_SB_CA<0>
  VSS33  = GND
  CA2_B  = M_D_CPU1_SB_CA<2>
  VSS34  = GND
  CA4_B  = M_D_CPU1_SB_CA<4>
  VSS35  = GND
  CA6_B  = M_D_CPU1_SB_CA<6>
  VSS36  = GND
  CS0_B_N  = M_D_CPU1_SB_CS_N<0>
  VSS37  = GND
  \lbd||rsp_a_n\  = M_D_CPU1_SA_RSP<0>
  \lbs||rsp_b_n\  = M_D_CPU1_SB_RSP<0>
  VSS38  = GND
  CB4_B  = M_D_CPU1_SB_CB<4>
  VSS39  = GND
  CB5_B  = M_D_CPU1_SB_CB<5>
  VSS40  = GND
  \dqs9_b_t||tdqs9_b_t||dbi4_b_n\  = M_D_CPU1_SB_DQS_DP<9>
  \dqs9_b_c||tdqs9_b_c\  = M_D_CPU1_SB_DQS_DN<9>
  VSS41  = GND
  CB0_B  = M_D_CPU1_SB_CB<0>
  VSS42  = GND
  CB1_B  = M_D_CPU1_SB_CB<1>
  VSS43  = GND
  DQ0_B  = M_D_CPU1_SB_DQ<0>
  VSS44  = GND
  DQ1_B  = M_D_CPU1_SB_DQ<1>
  VSS45  = GND
  DQS0_B_T  = M_D_CPU1_SB_DQS_DP<0>
  DQS0_B_C  = M_D_CPU1_SB_DQS_DN<0>
  VSS46  = GND
  DQ4_B  = M_D_CPU1_SB_DQ<4>
  VSS47  = GND
  DQ5_B  = M_D_CPU1_SB_DQ<5>
  VSS48  = GND
  DQ8_B  = M_D_CPU1_SB_DQ<8>
  VSS49  = GND
  DQ9_B  = M_D_CPU1_SB_DQ<9>
  VSS50  = GND
  DQS1_B_T  = M_D_CPU1_SB_DQS_DP<1>
  DQS1_B_C  = M_D_CPU1_SB_DQS_DN<1>
  VSS51  = GND
  DQ12_B  = M_D_CPU1_SB_DQ<12>
  VSS52  = GND
  DQ13_B  = M_D_CPU1_SB_DQ<13>
  VSS53  = GND
  DQ16_B  = M_D_CPU1_SB_DQ<16>
  VSS54  = GND
  DQ17_B  = M_D_CPU1_SB_DQ<17>
  VSS55  = GND
  DQS2_B_T  = M_D_CPU1_SB_DQS_DP<2>
  DQS2_B_C  = M_D_CPU1_SB_DQS_DN<2>
  VSS56  = GND
  DQ20_B  = M_D_CPU1_SB_DQ<20>
  VSS57  = GND
  DQ21_B  = M_D_CPU1_SB_DQ<21>
  VSS58  = GND
  DQ24_B  = M_D_CPU1_SB_DQ<24>
  VSS59  = GND
  DQ25_B  = M_D_CPU1_SB_DQ<25>
  VSS60  = GND
  DQS3_B_T  = M_D_CPU1_SB_DQS_DP<3>
  DQS3_B_C  = M_D_CPU1_SB_DQS_DN<3>
  VSS61  = GND
  DQ28_B  = M_D_CPU1_SB_DQ<28>
  VSS62  = GND
  DQ29_B  = M_D_CPU1_SB_DQ<29>
  VSS63  = GND
  RFU1  = TP_CHD_CPU1_DIMM1_FRU_1
  VIN_BULK1  = P12V_S3_AUX_CPU1_NVDIMM
  VIN_BULK2  = P12V_S3_AUX_CPU1_NVDIMM
  \pwr_good||fail_n\  = PWRGD_CHD_CPU1_DIMM1
  HSA  = PD_CHD_CPU1_DIMM1_SAA
  RFU2  = TP_CHD_CPU1_DIMM1_FRU_2
  RFU3  = TP_CHD_CPU1_DIMM1_FRU_3
  VSS64  = GND
  DQ2_A  = M_D_CPU1_SA_DQ<2>
  VSS65  = GND
  DQ3_A  = M_D_CPU1_SA_DQ<3>
  VSS66  = GND
  \dqs5_a_c||tdqs5_a_c||dqs5_a_t||tdqs5_a_t\  = M_D_CPU1_SA_DQS_DN<5>
  \dqs5_a_t||tdqs5_a_t\  = M_D_CPU1_SA_DQS_DP<5>
  VSS67  = GND
  DQ6_A  = M_D_CPU1_SA_DQ<6>
  VSS68  = GND
  DQ7_A  = M_D_CPU1_SA_DQ<7>
  VSS69  = GND
  DQ10_A  = M_D_CPU1_SA_DQ<10>
  VSS70  = GND
  DQ11_A  = M_D_CPU1_SA_DQ<11>
  VSS71  = GND
  \dqs6_a_c||tdqs6_a_c||dqs6_a_t||tdqs6_a_t\  = M_D_CPU1_SA_DQS_DN<6>
  \dqs6_a_t||tdqs6_a_t\  = M_D_CPU1_SA_DQS_DP<6>
  VSS72  = GND
  DQ14_A  = M_D_CPU1_SA_DQ<14>
  VSS73  = GND
  DQ15_A  = M_D_CPU1_SA_DQ<15>
  VSS74  = GND
  DQ18_A  = M_D_CPU1_SA_DQ<18>
  VSS75  = GND
  DQ19_A  = M_D_CPU1_SA_DQ<19>
  VSS76  = GND
  \dqs7_a_c||tdqs7_a_c\  = M_D_CPU1_SA_DQS_DN<7>
  \dqs7_a_t||tdqs7_a_t\  = M_D_CPU1_SA_DQS_DP<7>
  VSS77  = GND
  DQ22_A  = M_D_CPU1_SA_DQ<22>
  VSS78  = GND
  DQ23_A  = M_D_CPU1_SA_DQ<23>
  VSS79  = GND
  DQ26_A  = M_D_CPU1_SA_DQ<26>
  VSS80  = GND
  DQ27_A  = M_D_CPU1_SA_DQ<27>
  VSS81  = GND
  \dqs8_a_c||tdqs8_a_c\  = M_D_CPU1_SA_DQS_DN<8>
  \dqs8_a_t||tdqs8_a_t\  = M_D_CPU1_SA_DQS_DP<8>
  VSS82  = GND
  DQ30_A  = M_D_CPU1_SA_DQ<30>
  VSS83  = GND
  DQ31_A  = M_D_CPU1_SA_DQ<31>
  VSS84  = GND
  CB2_A  = M_D_CPU1_SA_CB<2>
  VSS85  = GND
  CB3_A  = M_D_CPU1_SA_CB<3>
  VSS86  = GND
  \dqs9_a_c||tdqs9_a_c\  = M_D_CPU1_SA_DQS_DN<9>
  \dqs9_a_t||tdqs9_a_t\  = M_D_CPU1_SA_DQS_DP<9>
  VSS87  = GND
  CB6_A  = M_D_CPU1_SA_CB<6>
  VSS88  = GND
  CB7_A  = M_D_CPU1_SA_CB<7>
  VSS89  = GND
  RESET_N  = RST_M_CD_CPU1_FPGA_N
  VSS90  = GND
  CS1_A_N  = M_D_CPU1_SA_CS_N<1>
  VSS91  = GND
  CA1_A  = M_D_CPU1_SA_CA<1>
  VSS92  = GND
  CA3_A  = M_D_CPU1_SA_CA<3>
  VSS93  = GND
  CA5_A  = M_D_CPU1_SA_CA<5>
  VSS94  = GND
  CK_T  = M_D_CPU1_CLK_DP<0>
  CK_C  = M_D_CPU1_CLK_DN<0>
  VSS95  = GND
  RFU4  = TP_CHD_CPU1_DIMM1_FRU_4
  CA1_B  = M_D_CPU1_SB_CA<1>
  VSS96  = GND
  CA3_B  = M_D_CPU1_SB_CA<3>
  VSS97  = GND
  CA5_B  = M_D_CPU1_SB_CA<5>
  VSS98  = GND
  PAR_B  = M_D_CPU1_SB_PAR
  VSS99  = GND
  CS1_B_N  = M_D_CPU1_SB_CS_N<1>
  VSS100  = GND
  RFU5  = TP_CHD_CPU1_DIMM1_FRU_5
  RFU6  = TP_CHD_CPU1_DIMM1_FRU_6
  VSS101  = GND
  CB6_B  = M_D_CPU1_SB_CB<6>
  VSS102  = GND
  CB7_B  = M_D_CPU1_SB_CB<7>
  VSS103  = GND
  DQS4_B_C  = M_D_CPU1_SB_DQS_DN<4>
  DQS4_B_T  = M_D_CPU1_SB_DQS_DP<4>
  VSS104  = GND
  CB2_B  = M_D_CPU1_SB_CB<2>
  VSS105  = GND
  CB3_B  = M_D_CPU1_SB_CB<3>
  VSS106  = GND
  DQ2_B  = M_D_CPU1_SB_DQ<2>
  VSS107  = GND
  DQ3_B  = M_D_CPU1_SB_DQ<3>
  VSS108  = GND
  \dqs5_b_c||tdqs5_b_c\  = M_D_CPU1_SB_DQS_DN<5>
  \dqs5_b_t||tdqs5_b_t\  = M_D_CPU1_SB_DQS_DP<5>
  VSS109  = GND
  DQ6_B  = M_D_CPU1_SB_DQ<6>
  VSS110  = GND
  DQ7_B  = M_D_CPU1_SB_DQ<7>
  VSS111  = GND
  DQ10_B  = M_D_CPU1_SB_DQ<10>
  VSS112  = GND
  DQ11_B  = M_D_CPU1_SB_DQ<11>
  VSS113  = GND
  \dqs6_b_c||tdqs6_b_c\  = M_D_CPU1_SB_DQS_DN<6>
  \dqs6_b_t||tdqs6_b_t\  = M_D_CPU1_SB_DQS_DP<6>
  VSS114  = GND
  DQ14_B  = M_D_CPU1_SB_DQ<14>
  VSS115  = GND
  DQ15_B  = M_D_CPU1_SB_DQ<15>
  VSS116  = GND
  DQ18_B  = M_D_CPU1_SB_DQ<18>
  VSS117  = GND
  DQ19_B  = M_D_CPU1_SB_DQ<19>
  VSS118  = GND
  \dqs7_b_c||tdqs7_b_c\  = M_D_CPU1_SB_DQS_DN<7>
  \dqs7_b_t||tdqs7_b_t\  = M_D_CPU1_SB_DQS_DP<7>
  VSS119  = GND
  DQ22_B  = M_D_CPU1_SB_DQ<22>
  VSS120  = GND
  DQ23_B  = M_D_CPU1_SB_DQ<23>
  VSS121  = GND
  DQ26_B  = M_D_CPU1_SB_DQ<26>
  VSS122  = GND
  DQ27_B  = M_D_CPU1_SB_DQ<27>
  VSS123  = GND
  \dqs8_b_c||tdqs8_b_c\  = M_D_CPU1_SB_DQS_DN<8>
  \dqs8_b_t||tdqs8_b_t\  = M_D_CPU1_SB_DQS_DP<8>
  VSS124  = GND
  DQ30_B  = M_D_CPU1_SB_DQ<30>
  VSS125  = GND
  DQ31_B  = M_D_CPU1_SB_DQ<31>
  VSS126  = GND
  G1  = GND
  G2  = GND
  G3  = GND

(kicad_pcb
	(version 20260206)
	(generator "pcbnew")
	(generator_version "10.0")
	(general
		(thickness 1.6)
		(legacy_teardrops no)
	)
	(paper "A4")
	(title_block
		(title "03242023_DA0F0TMBIJ0_F0T_Motherboard_J_brd_V01_OCP.brd")
		(comment 1 "Grand Teton / footprint 3586 of 6105 (J23), pads 229-274 of 291")
	)
	(layers
		(0 "F.Cu" signal "TOP")
		(4 "In1.Cu" signal "GND")
		(6 "In2.Cu" signal "IN1")
		(8 "In3.Cu" signal "GND1")
		(10 "In4.Cu" signal "IN2")
		(12 "In5.Cu" signal "GND2")
		(14 "In6.Cu" signal "IN3")
		(16 "In7.Cu" signal "GND3")
		(18 "In8.Cu" signal "VCC")
		(20 "In9.Cu" signal "VCC1")
		(22 "In10.Cu" signal "GND4")
		(24 "In11.Cu" signal "IN4")
		(26 "In12.Cu" signal "GND5")
		(28 "In13.Cu" signal "IN5")
		(30 "In14.Cu" signal "GND6")
		(32 "In15.Cu" signal "IN6")
		(34 "In16.Cu" signal "GND7")
		(2 "B.Cu" signal "BOTTOM")
		(9 "F.Adhes" user "F.Adhesive")
		(11 "B.Adhes" user "B.Adhesive")
		(13 "F.Paste" user "Package Geometry/Pastemask Top")
		(15 "B.Paste" user "Package Geometry/Pastemask Bottom")
		(5 "F.SilkS" user "Ref Des/Silkscreen Top")
		(7 "B.SilkS" user "Ref Des/Silkscreen Bottom")
		(1 "F.Mask" user "Board Geometry/Soldermask Top")
		(3 "B.Mask" user "Board Geometry/Soldermask Bottom")
		(17 "Dwgs.User" user "User.Drawings")
		(19 "Cmts.User" user "User.Comments")
		(21 "Eco1.User" user "User.Eco1")
		(23 "Eco2.User" user "User.Eco2")
		(25 "Edge.Cuts" user "Board Geometry/Outline")
		(27 "Margin" user)
		(31 "F.CrtYd" user "Package Geometry/Place Bound Top")
		(29 "B.CrtYd" user "Package Geometry/Place Bound Bottom")
		(35 "F.Fab" user "Ref Des/Assembly Top")
		(33 "B.Fab" user "Ref Des/Assembly Bottom")
	)
	(footprint ""
		(layer "F.Cu")
		(at 10.19048 -258.091686)
		(property "Reference" "J23"
			(at -5.69468 -80.480408 0)
			(unlocked yes)
			(layer "F.SilkS")
			(effects
				(font
					(size 0.7874 0.5842)
					(thickness 0.1524)
				)
				(justify left)
			)
		)
		(property "Value" ""
			(at 0 0 0)
			(layer "F.Fab")
			(effects
				(font
					(size 1.27 1.27)
				)
			)
		)
		(duplicate_pad_numbers_are_jumpers no)
		(pad "229" smd rect
			(at 2.050034 13.17498 270)
			(size 0.519938 1.4986)
			(layers "F.Cu" "F.Mask" "F.Paste")
			(net "M_D_CPU1_SB_CS_N<1>")
		)
		(pad "230" smd rect
			(at 2.050034 14.025118 270)
			(size 0.519938 1.4986)
			(layers "F.Cu" "F.Mask" "F.Paste")
			(net "GND")
		)
		(pad "231" smd rect
			(at 2.050034 14.875002 270)
			(size 0.519938 1.4986)
			(layers "F.Cu" "F.Mask" "F.Paste")
			(net "TP_CHD_CPU1_DIMM1_FRU_5")
		)
		(pad "232" smd rect
			(at 2.050034 15.724886 270)
			(size 0.519938 1.4986)
			(layers "F.Cu" "F.Mask" "F.Paste")
			(net "TP_CHD_CPU1_DIMM1_FRU_6")
		)
		(pad "233" smd rect
			(at 2.050034 16.575024 270)
			(size 0.519938 1.4986)
			(layers "F.Cu" "F.Mask" "F.Paste")
			(net "GND")
		)
		(pad "234" smd rect
			(at 2.050034 17.424908 270)
			(size 0.519938 1.4986)
			(layers "F.Cu" "F.Mask" "F.Paste")
			(net "M_D_CPU1_SB_CB<6>")
		)
		(pad "235" smd rect
			(at 2.050034 18.275046 270)
			(size 0.519938 1.4986)
			(layers "F.Cu" "F.Mask" "F.Paste")
			(net "GND")
		)
		(pad "236" smd rect
			(at 2.050034 19.12493 270)
			(size 0.519938 1.4986)
			(layers "F.Cu" "F.Mask" "F.Paste")
			(net "M_D_CPU1_SB_CB<7>")
		)
		(pad "237" smd rect
			(at 2.050034 19.975068 270)
			(size 0.519938 1.4986)
			(layers "F.Cu" "F.Mask" "F.Paste")
			(net "GND")
		)
		(pad "238" smd rect
			(at 2.050034 20.824952 270)
			(size 0.519938 1.4986)
			(layers "F.Cu" "F.Mask" "F.Paste")
			(net "M_D_CPU1_SB_DQS_DN<4>")
		)
		(pad "239" smd rect
			(at 2.050034 21.67509 270)
			(size 0.519938 1.4986)
			(layers "F.Cu" "F.Mask" "F.Paste")
			(net "M_D_CPU1_SB_DQS_DP<4>")
		)
		(pad "240" smd rect
			(at 2.050034 22.524974 270)
			(size 0.519938 1.4986)
			(layers "F.Cu" "F.Mask" "F.Paste")
			(net "GND")
		)
		(pad "241" smd rect
			(at 2.050034 23.375112 270)
			(size 0.519938 1.4986)
			(layers "F.Cu" "F.Mask" "F.Paste")
			(net "M_D_CPU1_SB_CB<2>")
		)
		(pad "242" smd rect
			(at 2.050034 24.224996 270)
			(size 0.519938 1.4986)
			(layers "F.Cu" "F.Mask" "F.Paste")
			(net "GND")
		)
		(pad "243" smd rect
			(at 2.050034 25.07488 270)
			(size 0.519938 1.4986)
			(layers "F.Cu" "F.Mask" "F.Paste")
			(net "M_D_CPU1_SB_CB<3>")
		)
		(pad "244" smd rect
			(at 2.050034 25.925018 270)
			(size 0.519938 1.4986)
			(layers "F.Cu" "F.Mask" "F.Paste")
			(net "GND")
		)
		(pad "245" smd rect
			(at 2.050034 26.774902 270)
			(size 0.519938 1.4986)
			(layers "F.Cu" "F.Mask" "F.Paste")
			(net "M_D_CPU1_SB_DQ<2>")
		)
		(pad "246" smd rect
			(at 2.050034 27.62504 270)
			(size 0.519938 1.4986)
			(layers "F.Cu" "F.Mask" "F.Paste")
			(net "GND")
		)
		(pad "247" smd rect
			(at 2.050034 28.474924 270)
			(size 0.519938 1.4986)
			(layers "F.Cu" "F.Mask" "F.Paste")
			(net "M_D_CPU1_SB_DQ<3>")
		)
		(pad "248" smd rect
			(at 2.050034 29.325062 270)
			(size 0.519938 1.4986)
			(layers "F.Cu" "F.Mask" "F.Paste")
			(net "GND")
		)
		(pad "249" smd rect
			(at 2.050034 30.174946 270)
			(size 0.519938 1.4986)
			(layers "F.Cu" "F.Mask" "F.Paste")
			(net "M_D_CPU1_SB_DQS_DN<5>")
		)
		(pad "250" smd rect
			(at 2.050034 31.025084 270)
			(size 0.519938 1.4986)
			(layers "F.Cu" "F.Mask" "F.Paste")
			(net "M_D_CPU1_SB_DQS_DP<5>")
		)
		(pad "251" smd rect
			(at 2.050034 31.874968 270)
			(size 0.519938 1.4986)
			(layers "F.Cu" "F.Mask" "F.Paste")
			(net "GND")
		)
		(pad "252" smd rect
			(at 2.050034 32.725106 270)
			(size 0.519938 1.4986)
			(layers "F.Cu" "F.Mask" "F.Paste")
			(net "M_D_CPU1_SB_DQ<6>")
		)
		(pad "253" smd rect
			(at 2.050034 33.57499 270)
			(size 0.519938 1.4986)
			(layers "F.Cu" "F.Mask" "F.Paste")
			(net "GND")
		)
		(pad "254" smd rect
			(at 2.050034 34.425128 270)
			(size 0.519938 1.4986)
			(layers "F.Cu" "F.Mask" "F.Paste")
			(net "M_D_CPU1_SB_DQ<7>")
		)
		(pad "255" smd rect
			(at 2.050034 35.275012 270)
			(size 0.519938 1.4986)
			(layers "F.Cu" "F.Mask" "F.Paste")
			(net "GND")
		)
		(pad "256" smd rect
			(at 2.050034 36.124896 270)
			(size 0.519938 1.4986)
			(layers "F.Cu" "F.Mask" "F.Paste")
			(net "M_D_CPU1_SB_DQ<10>")
		)
		(pad "257" smd rect
			(at 2.050034 36.975034 270)
			(size 0.519938 1.4986)
			(layers "F.Cu" "F.Mask" "F.Paste")
			(net "GND")
		)
		(pad "258" smd rect
			(at 2.050034 37.824918 270)
			(size 0.519938 1.4986)
			(layers "F.Cu" "F.Mask" "F.Paste")
			(net "M_D_CPU1_SB_DQ<11>")
		)
		(pad "259" smd rect
			(at 2.050034 38.675056 270)
			(size 0.519938 1.4986)
			(layers "F.Cu" "F.Mask" "F.Paste")
			(net "GND")
		)
		(pad "260" smd rect
			(at 2.050034 39.52494 270)
			(size 0.519938 1.4986)
			(layers "F.Cu" "F.Mask" "F.Paste")
			(net "M_D_CPU1_SB_DQS_DN<6>")
		)
		(pad "261" smd rect
			(at 2.050034 40.375078 270)
			(size 0.519938 1.4986)
			(layers "F.Cu" "F.Mask" "F.Paste")
			(net "M_D_CPU1_SB_DQS_DP<6>")
		)
		(pad "262" smd rect
			(at 2.050034 41.224962 270)
			(size 0.519938 1.4986)
			(layers "F.Cu" "F.Mask" "F.Paste")
			(net "GND")
		)
		(pad "263" smd rect
			(at 2.050034 42.0751 270)
			(size 0.519938 1.4986)
			(layers "F.Cu" "F.Mask" "F.Paste")
			(net "M_D_CPU1_SB_DQ<14>")
		)
		(pad "264" smd rect
			(at 2.050034 42.924984 270)
			(size 0.519938 1.4986)
			(layers "F.Cu" "F.Mask" "F.Paste")
			(net "GND")
		)
		(pad "265" smd rect
			(at 2.050034 43.775122 270)
			(size 0.519938 1.4986)
			(layers "F.Cu" "F.Mask" "F.Paste")
			(net "M_D_CPU1_SB_DQ<15>")
		)
		(pad "266" smd rect
			(at 2.050034 44.625006 270)
			(size 0.519938 1.4986)
			(layers "F.Cu" "F.Mask" "F.Paste")
			(net "GND")
		)
		(pad "267" smd rect
			(at 2.050034 45.47489 270)
			(size 0.519938 1.4986)
			(layers "F.Cu" "F.Mask" "F.Paste")
			(net "M_D_CPU1_SB_DQ<18>")
		)
		(pad "268" smd rect
			(at 2.050034 46.325028 270)
			(size 0.519938 1.4986)
			(layers "F.Cu" "F.Mask" "F.Paste")
			(net "GND")
		)
		(pad "269" smd rect
			(at 2.050034 47.174912 270)
			(size 0.519938 1.4986)
			(layers "F.Cu" "F.Mask" "F.Paste")
			(net "M_D_CPU1_SB_DQ<19>")
		)
		(pad "270" smd rect
			(at 2.050034 48.02505 270)
			(size 0.519938 1.4986)
			(layers "F.Cu" "F.Mask" "F.Paste")
			(net "GND")
		)
		(pad "271" smd rect
			(at 2.050034 48.874934 270)
			(size 0.519938 1.4986)
			(layers "F.Cu" "F.Mask" "F.Paste")
			(net "M_D_CPU1_SB_DQS_DN<7>")
		)
		(pad "272" smd rect
			(at 2.050034 49.725072 270)
			(size 0.519938 1.4986)
			(layers "F.Cu" "F.Mask" "F.Paste")
			(net "M_D_CPU1_SB_DQS_DP<7>")
		)
		(pad "273" smd rect
			(at 2.050034 50.574956 270)
			(size 0.519938 1.4986)
			(layers "F.Cu" "F.Mask" "F.Paste")
			(net "GND")
		)
		(pad "274" smd rect
			(at 2.050034 51.425094 270)
			(size 0.519938 1.4986)
			(layers "F.Cu" "F.Mask" "F.Paste")
			(net "M_D_CPU1_SB_DQ<22>")
		)
	)
)
